# T6G (Grand Teton) — schematic netlist excerpt (pin names and nets, part order shuffled) for the footprints in the layout excerpt that follows; sources: Cadence DE-HDL packaged netlist, KiCad conversion of 04192023_DAF0TMB3IC0_F0TG_MB_C_brd_V02_OCP.brd

R958  Q_RES  33 5% CHIP  pkg 0402LF  page 82 : A = FM_PLD_OCP_SFF_AUX_PWR_EN ; B = FM_PLD_OCP_SFF_AUX_PWR_R_EN
C626  Q_CAP  10UF 6.3V 20% X6S  pkg C0402  page 290 : A = P0V9_CPU0_RT1_2A ; B = GND

(kicad_pcb
	(version 20260206)
	(generator "pcbnew")
	(generator_version "10.0")
	(general
		(thickness 1.6)
		(legacy_teardrops no)
	)
	(paper "A4")
	(title_block
		(title "04192023_DAF0TMB3IC0_F0TG_MB_C_brd_V02_OCP.brd")
		(comment 1 "Grand Teton / footprints 7128-7129 of 8354")
	)
	(layers
		(0 "F.Cu" signal "TOP")
		(4 "In1.Cu" signal "GND")
		(6 "In2.Cu" signal "IN1")
		(8 "In3.Cu" signal "GND1")
		(10 "In4.Cu" signal "IN2")
		(12 "In5.Cu" signal "GND2")
		(14 "In6.Cu" signal "IN3")
		(16 "In7.Cu" signal "GND3")
		(18 "In8.Cu" signal "VCC")
		(20 "In9.Cu" signal "VCC1")
		(22 "In10.Cu" signal "GND4")
		(24 "In11.Cu" signal "IN4")
		(26 "In12.Cu" signal "GND5")
		(28 "In13.Cu" signal "IN5")
		(30 "In14.Cu" signal "GND6")
		(32 "In15.Cu" signal "IN6")
		(34 "In16.Cu" signal "GND7")
		(2 "B.Cu" signal "BOTTOM")
		(9 "F.Adhes" user "F.Adhesive")
		(11 "B.Adhes" user "B.Adhesive")
		(13 "F.Paste" user "Package Geometry/Pastemask Top")
		(15 "B.Paste" user "Package Geometry/Pastemask Bottom")
		(5 "F.SilkS" user "Ref Des/Silkscreen Top")
		(7 "B.SilkS" user "Ref Des/Silkscreen Bottom")
		(1 "F.Mask" user "Board Geometry/Soldermask Top")
		(3 "B.Mask" user "Board Geometry/Soldermask Bottom")
		(17 "Dwgs.User" user "User.Drawings")
		(19 "Cmts.User" user "User.Comments")
		(21 "Eco1.User" user "User.Eco1")
		(23 "Eco2.User" user "User.Eco2")
		(25 "Edge.Cuts" user "Board Geometry/Outline")
		(27 "Margin" user)
		(31 "F.CrtYd" user "Package Geometry/Place Bound Top")
		(29 "B.CrtYd" user "Package Geometry/Place Bound Bottom")
		(35 "F.Fab" user "Ref Des/Assembly Top")
		(33 "B.Fab" user "Ref Des/Assembly Bottom")
	)
	(footprint ""
		(layer "B.Cu")
		(at 185.801 -100.294948 -90)
		(property "Reference" "R958"
			(at 0 0 90)
			(layer "B.SilkS")
			(hide yes)
			(effects
				(font
					(size 1.27 1.27)
				)
				(justify mirror)
			)
		)
		(property "Value" ""
			(at 0 0 90)
			(layer "B.Fab")
			(effects
				(font
					(size 1.27 1.27)
				)
				(justify mirror)
			)
		)
		(duplicate_pad_numbers_are_jumpers no)
		(fp_line
			(start -0.7874 0.4064)
			(end 0.7874 0.4064)
			(stroke
				(width 0.1524)
				(type default)
			)
			(layer "B.SilkS")
		)
		(fp_line
			(start 0.7874 0.4064)
			(end 0.7874 -0.4064)
			(stroke
				(width 0.1524)
				(type default)
			)
			(layer "B.SilkS")
		)
		(fp_line
			(start -0.7874 -0.4064)
			(end -0.7874 0.4064)
			(stroke
				(width 0.1524)
				(type default)
			)
			(layer "B.SilkS")
		)
		(fp_line
			(start 0.7874 -0.4064)
			(end -0.7874 -0.4064)
			(stroke
				(width 0.1524)
				(type default)
			)
			(layer "B.SilkS")
		)
		(fp_line
			(start -0.67945 0.3048)
			(end -0.120396 0.3048)
			(stroke
				(width 0.1)
				(type default)
			)
			(layer "B.Fab")
		)
		(fp_line
			(start -0.120396 0.3048)
			(end -0.120396 0.2794)
			(stroke
				(width 0.1)
				(type default)
			)
			(layer "B.Fab")
		)
		(fp_line
			(start 0.12065 0.3048)
			(end 0.67945 0.3048)
			(stroke
				(width 0.1)
				(type default)
			)
			(layer "B.Fab")
		)
		(fp_line
			(start 0.67945 0.3048)
			(end 0.67945 -0.305054)
			(stroke
				(width 0.1)
				(type default)
			)
			(layer "B.Fab")
		)
		(fp_line
			(start -0.120396 0.2794)
			(end 0.12065 0.2794)
			(stroke
				(width 0.1)
				(type default)
			)
			(layer "B.Fab")
		)
		(fp_line
			(start 0.12065 0.2794)
			(end 0.12065 0.3048)
			(stroke
				(width 0.1)
				(type default)
			)
			(layer "B.Fab")
		)
		(fp_line
			(start -0.12065 -0.2794)
			(end -0.12065 -0.3048)
			(stroke
				(width 0.1)
				(type default)
			)
			(layer "B.Fab")
		)
		(fp_line
			(start 0.12065 -0.2794)
			(end -0.12065 -0.2794)
			(stroke
				(width 0.1)
				(type default)
			)
			(layer "B.Fab")
		)
		(fp_line
			(start -0.67945 -0.3048)
			(end -0.67945 0.3048)
			(stroke
				(width 0.1)
				(type default)
			)
			(layer "B.Fab")
		)
		(fp_line
			(start -0.12065 -0.3048)
			(end -0.67945 -0.3048)
			(stroke
				(width 0.1)
				(type default)
			)
			(layer "B.Fab")
		)
		(fp_line
			(start 0.12065 -0.305054)
			(end 0.12065 -0.2794)
			(stroke
				(width 0.1)
				(type default)
			)
			(layer "B.Fab")
		)
		(fp_line
			(start 0.67945 -0.305054)
			(end 0.12065 -0.305054)
			(stroke
				(width 0.1)
				(type default)
			)
			(layer "B.Fab")
		)
		(pad "1" smd circle
			(at 0.40005 0 90)
			(size 0 0)
			(layers "B.Cu" "B.Mask" "B.Paste")
			(net "FM_PLD_OCP_SFF_AUX_PWR_EN")
		)
		(pad "2" smd circle
			(at -0.40005 0 90)
			(size 0 0)
			(layers "B.Cu" "B.Mask" "B.Paste")
			(net "FM_PLD_OCP_SFF_AUX_PWR_R_EN")
		)
	)
	(footprint ""
		(layer "B.Cu")
		(at 339.518752 -398.942052 90)
		(property "Reference" "C626"
			(at 0 0 90)
			(layer "B.SilkS")
			(hide yes)
			(effects
				(font
					(size 1.27 1.27)
				)
				(justify mirror)
			)
		)
		(property "Value" ""
			(at 0 0 90)
			(layer "B.Fab")
			(effects
				(font
					(size 1.27 1.27)
				)
				(justify mirror)
			)
		)
		(duplicate_pad_numbers_are_jumpers no)
		(fp_line
			(start 0.7874 -0.4064)
			(end -0.7874 -0.4064)
			(stroke
				(width 0.1524)
				(type default)
			)
			(layer "B.SilkS")
		)
		(fp_line
			(start -0.7874 -0.4064)
			(end -0.7874 0.4064)
			(stroke
				(width 0.1524)
				(type default)
			)
			(layer "B.SilkS")
		)
		(fp_line
			(start 0.7874 0.4064)
			(end 0.7874 -0.4064)
			(stroke
				(width 0.1524)
				(type default)
			)
			(layer "B.SilkS")
		)
		(fp_line
			(start -0.7874 0.4064)
			(end 0.7874 0.4064)
			(stroke
				(width 0.1524)
				(type default)
			)
			(layer "B.SilkS")
		)
		(fp_line
			(start 0.67945 -0.305054)
			(end 0.12065 -0.305054)
			(stroke
				(width 0.1)
				(type default)
			)
			(layer "B.Fab")
		)
		(fp_line
			(start 0.12065 -0.305054)
			(end 0.12065 -0.2794)
			(stroke
				(width 0.1)
				(type default)
			)
			(layer "B.Fab")
		)
		(fp_line
			(start -0.12065 -0.3048)
			(end -0.67945 -0.3048)
			(stroke
				(width 0.1)
				(type default)
			)
			(layer "B.Fab")
		)
		(fp_line
			(start -0.67945 -0.3048)
			(end -0.67945 0.3048)
			(stroke
				(width 0.1)
				(type default)
			)
			(layer "B.Fab")
		)
		(fp_line
			(start 0.12065 -0.2794)
			(end -0.12065 -0.2794)
			(stroke
				(width 0.1)
				(type default)
			)
			(layer "B.Fab")
		)
		(fp_line
			(start -0.12065 -0.2794)
			(end -0.12065 -0.3048)
			(stroke
				(width 0.1)
				(type default)
			)
			(layer "B.Fab")
		)
		(fp_line
			(start 0.12065 0.2794)
			(end 0.12065 0.3048)
			(stroke
				(width 0.1)
				(type default)
			)
			(layer "B.Fab")
		)
		(fp_line
			(start -0.120396 0.2794)
			(end 0.12065 0.2794)
			(stroke
				(width 0.1)
				(type default)
			)
			(layer "B.Fab")
		)
		(fp_line
			(start 0.67945 0.3048)
			(end 0.67945 -0.305054)
			(stroke
				(width 0.1)
				(type default)
			)
			(layer "B.Fab")
		)
		(fp_line
			(start 0.12065 0.3048)
			(end 0.67945 0.3048)
			(stroke
				(width 0.1)
				(type default)
			)
			(layer "B.Fab")
		)
		(fp_line
			(start -0.120396 0.3048)
			(end -0.120396 0.2794)
			(stroke
				(width 0.1)
				(type default)
			)
			(layer "B.Fab")
		)
		(fp_line
			(start -0.67945 0.3048)
			(end -0.120396 0.3048)
			(stroke
				(width 0.1)
				(type default)
			)
			(layer "B.Fab")
		)
		(pad "1" smd circle
			(at 0.40005 0 270)
			(size 0 0)
			(layers "B.Cu" "B.Mask" "B.Paste")
			(net "P0V9_CPU0_RT1_2A")
		)
		(pad "2" smd circle
			(at -0.40005 0 270)
			(size 0 0)
			(layers "B.Cu" "B.Mask" "B.Paste")
			(net "GND")
		)
	)
)
